(kicad_pcb
	(version 20260206)
	(generator "pcbnew")
	(generator_version "10.0")
	(general
		(thickness 1.6)
		(legacy_teardrops no)
	)
	(paper "A4")
	(title_block
		(title "03242023_DA0F0TMBIJ0_F0T_Motherboard_J_brd_V01_OCP.brd")
		(comment 1 "Grand Teton / footprints 4591-4596 of 6105")
	)
	(layers
		(0 "F.Cu" signal "TOP")
		(4 "In1.Cu" signal "GND")
		(6 "In2.Cu" signal "IN1")
		(8 "In3.Cu" signal "GND1")
		(10 "In4.Cu" signal "IN2")
		(12 "In5.Cu" signal "GND2")
		(14 "In6.Cu" signal "IN3")
		(16 "In7.Cu" signal "GND3")
		(18 "In8.Cu" signal "VCC")
		(20 "In9.Cu" signal "VCC1")
		(22 "In10.Cu" signal "GND4")
		(24 "In11.Cu" signal "IN4")
		(26 "In12.Cu" signal "GND5")
		(28 "In13.Cu" signal "IN5")
		(30 "In14.Cu" signal "GND6")
		(32 "In15.Cu" signal "IN6")
		(34 "In16.Cu" signal "GND7")
		(2 "B.Cu" signal "BOTTOM")
		(9 "F.Adhes" user "F.Adhesive")
		(11 "B.Adhes" user "B.Adhesive")
		(13 "F.Paste" user "Package Geometry/Pastemask Top")
		(15 "B.Paste" user "Package Geometry/Pastemask Bottom")
		(5 "F.SilkS" user "Ref Des/Silkscreen Top")
		(7 "B.SilkS" user "Ref Des/Silkscreen Bottom")
		(1 "F.Mask" user "Board Geometry/Soldermask Top")
		(3 "B.Mask" user "Board Geometry/Soldermask Bottom")
		(17 "Dwgs.User" user "User.Drawings")
		(19 "Cmts.User" user "User.Comments")
		(21 "Eco1.User" user "User.Eco1")
		(23 "Eco2.User" user "User.Eco2")
		(25 "Edge.Cuts" user "Board Geometry/Outline")
		(27 "Margin" user)
		(31 "F.CrtYd" user "Package Geometry/Place Bound Top")
		(29 "B.CrtYd" user "Package Geometry/Place Bound Bottom")
		(35 "F.Fab" user "Ref Des/Assembly Top")
		(33 "B.Fab" user "Ref Des/Assembly Bottom")
	)
	(footprint ""
		(layer "B.Cu")
		(at 99.26828 -325.084948 -90)
		(property "Reference" "PR4240"
			(at 0 0 90)
			(layer "B.SilkS")
			(hide yes)
			(effects
				(font
					(size 1.27 1.27)
				)
				(justify mirror)
			)
		)
		(property "Value" ""
			(at 0 0 90)
			(layer "B.Fab")
			(effects
				(font
					(size 1.27 1.27)
				)
				(justify mirror)
			)
		)
		(duplicate_pad_numbers_are_jumpers no)
		(fp_line
			(start -0.7874 0.4064)
			(end 0.7874 0.4064)
			(stroke
				(width 0.1524)
				(type default)
			)
			(layer "B.SilkS")
		)
		(fp_line
			(start 0.7874 0.4064)
			(end 0.7874 -0.4064)
			(stroke
				(width 0.1524)
				(type default)
			)
			(layer "B.SilkS")
		)
		(fp_line
			(start -0.7874 -0.4064)
			(end -0.7874 0.4064)
			(stroke
				(width 0.1524)
				(type default)
			)
			(layer "B.SilkS")
		)
		(fp_line
			(start 0.7874 -0.4064)
			(end -0.7874 -0.4064)
			(stroke
				(width 0.1524)
				(type default)
			)
			(layer "B.SilkS")
		)
		(fp_line
			(start -0.67945 0.3048)
			(end -0.120396 0.3048)
			(stroke
				(width 0.1)
				(type default)
			)
			(layer "B.Fab")
		)
		(fp_line
			(start -0.120396 0.3048)
			(end -0.120396 0.2794)
			(stroke
				(width 0.1)
				(type default)
			)
			(layer "B.Fab")
		)
		(fp_line
			(start 0.12065 0.3048)
			(end 0.67945 0.3048)
			(stroke
				(width 0.1)
				(type default)
			)
			(layer "B.Fab")
		)
		(fp_line
			(start 0.67945 0.3048)
			(end 0.67945 -0.305054)
			(stroke
				(width 0.1)
				(type default)
			)
			(layer "B.Fab")
		)
		(fp_line
			(start -0.120396 0.2794)
			(end 0.12065 0.2794)
			(stroke
				(width 0.1)
				(type default)
			)
			(layer "B.Fab")
		)
		(fp_line
			(start 0.12065 0.2794)
			(end 0.12065 0.3048)
			(stroke
				(width 0.1)
				(type default)
			)
			(layer "B.Fab")
		)
		(fp_line
			(start -0.12065 -0.2794)
			(end -0.12065 -0.3048)
			(stroke
				(width 0.1)
				(type default)
			)
			(layer "B.Fab")
		)
		(fp_line
			(start 0.12065 -0.2794)
			(end -0.12065 -0.2794)
			(stroke
				(width 0.1)
				(type default)
			)
			(layer "B.Fab")
		)
		(fp_line
			(start -0.67945 -0.3048)
			(end -0.67945 0.3048)
			(stroke
				(width 0.1)
				(type default)
			)
			(layer "B.Fab")
		)
		(fp_line
			(start -0.12065 -0.3048)
			(end -0.67945 -0.3048)
			(stroke
				(width 0.1)
				(type default)
			)
			(layer "B.Fab")
		)
		(fp_line
			(start 0.12065 -0.305054)
			(end 0.12065 -0.2794)
			(stroke
				(width 0.1)
				(type default)
			)
			(layer "B.Fab")
		)
		(fp_line
			(start 0.67945 -0.305054)
			(end 0.12065 -0.305054)
			(stroke
				(width 0.1)
				(type default)
			)
			(layer "B.Fab")
		)
		(pad "1" smd circle
			(at 0.40005 0 90)
			(size 0 0)
			(layers "B.Cu" "B.Mask" "B.Paste")
			(net "PVCCIN_CPU1")
		)
		(pad "2" smd circle
			(at -0.40005 0 90)
			(size 0 0)
			(layers "B.Cu" "B.Mask" "B.Paste")
			(net "GND")
		)
	)
	(footprint ""
		(layer "B.Cu")
		(at 374.562624 -190.703454 90)
		(property "Reference" "R909"
			(at 0 0 90)
			(layer "B.SilkS")
			(hide yes)
			(effects
				(font
					(size 1.27 1.27)
				)
				(justify mirror)
			)
		)
		(property "Value" ""
			(at 0 0 90)
			(layer "B.Fab")
			(effects
				(font
					(size 1.27 1.27)
				)
				(justify mirror)
			)
		)
		(duplicate_pad_numbers_are_jumpers no)
		(fp_line
			(start 0.7874 -0.4064)
			(end -0.7874 -0.4064)
			(stroke
				(width 0.1524)
				(type default)
			)
			(layer "B.SilkS")
		)
		(fp_line
			(start -0.7874 -0.4064)
			(end -0.7874 0.4064)
			(stroke
				(width 0.1524)
				(type default)
			)
			(layer "B.SilkS")
		)
		(fp_line
			(start 0.7874 0.4064)
			(end 0.7874 -0.4064)
			(stroke
				(width 0.1524)
				(type default)
			)
			(layer "B.SilkS")
		)
		(fp_line
			(start -0.7874 0.4064)
			(end 0.7874 0.4064)
			(stroke
				(width 0.1524)
				(type default)
			)
			(layer "B.SilkS")
		)
		(fp_line
			(start 0.67945 -0.305054)
			(end 0.12065 -0.305054)
			(stroke
				(width 0.1)
				(type default)
			)
			(layer "B.Fab")
		)
		(fp_line
			(start 0.12065 -0.305054)
			(end 0.12065 -0.2794)
			(stroke
				(width 0.1)
				(type default)
			)
			(layer "B.Fab")
		)
		(fp_line
			(start -0.12065 -0.3048)
			(end -0.67945 -0.3048)
			(stroke
				(width 0.1)
				(type default)
			)
			(layer "B.Fab")
		)
		(fp_line
			(start -0.67945 -0.3048)
			(end -0.67945 0.3048)
			(stroke
				(width 0.1)
				(type default)
			)
			(layer "B.Fab")
		)
		(fp_line
			(start 0.12065 -0.2794)
			(end -0.12065 -0.2794)
			(stroke
				(width 0.1)
				(type default)
			)
			(layer "B.Fab")
		)
		(fp_line
			(start -0.12065 -0.2794)
			(end -0.12065 -0.3048)
			(stroke
				(width 0.1)
				(type default)
			)
			(layer "B.Fab")
		)
		(fp_line
			(start 0.12065 0.2794)
			(end 0.12065 0.3048)
			(stroke
				(width 0.1)
				(type default)
			)
			(layer "B.Fab")
		)
		(fp_line
			(start -0.120396 0.2794)
			(end 0.12065 0.2794)
			(stroke
				(width 0.1)
				(type default)
			)
			(layer "B.Fab")
		)
		(fp_line
			(start 0.67945 0.3048)
			(end 0.67945 -0.305054)
			(stroke
				(width 0.1)
				(type default)
			)
			(layer "B.Fab")
		)
		(fp_line
			(start 0.12065 0.3048)
			(end 0.67945 0.3048)
			(stroke
				(width 0.1)
				(type default)
			)
			(layer "B.Fab")
		)
		(fp_line
			(start -0.120396 0.3048)
			(end -0.120396 0.2794)
			(stroke
				(width 0.1)
				(type default)
			)
			(layer "B.Fab")
		)
		(fp_line
			(start -0.67945 0.3048)
			(end -0.120396 0.3048)
			(stroke
				(width 0.1)
				(type default)
			)
			(layer "B.Fab")
		)
		(pad "1" smd circle
			(at 0.40005 0 270)
			(size 0 0)
			(layers "B.Cu" "B.Mask" "B.Paste")
			(net "SMB_PEHPCPU0_GTL_SDA")
		)
		(pad "2" smd circle
			(at -0.40005 0 270)
			(size 0 0)
			(layers "B.Cu" "B.Mask" "B.Paste")
			(net "SMB_PEHPCPU0_GTL_R_SDA")
		)
	)
	(footprint ""
		(layer "B.Cu")
		(at 303.554638 -192.457578 90)
		(property "Reference" "R548"
			(at 0 0 90)
			(layer "B.SilkS")
			(hide yes)
			(effects
				(font
					(size 1.27 1.27)
				)
				(justify mirror)
			)
		)
		(property "Value" ""
			(at 0 0 90)
			(layer "B.Fab")
			(effects
				(font
					(size 1.27 1.27)
				)
				(justify mirror)
			)
		)
		(duplicate_pad_numbers_are_jumpers no)
		(fp_line
			(start 0.7874 -0.4064)
			(end -0.7874 -0.4064)
			(stroke
				(width 0.1524)
				(type default)
			)
			(layer "B.SilkS")
		)
		(fp_line
			(start -0.7874 -0.4064)
			(end -0.7874 0.4064)
			(stroke
				(width 0.1524)
				(type default)
			)
			(layer "B.SilkS")
		)
		(fp_line
			(start 0.7874 0.4064)
			(end 0.7874 -0.4064)
			(stroke
				(width 0.1524)
				(type default)
			)
			(layer "B.SilkS")
		)
		(fp_line
			(start -0.7874 0.4064)
			(end 0.7874 0.4064)
			(stroke
				(width 0.1524)
				(type default)
			)
			(layer "B.SilkS")
		)
		(fp_line
			(start 0.67945 -0.305054)
			(end 0.12065 -0.305054)
			(stroke
				(width 0.1)
				(type default)
			)
			(layer "B.Fab")
		)
		(fp_line
			(start 0.12065 -0.305054)
			(end 0.12065 -0.2794)
			(stroke
				(width 0.1)
				(type default)
			)
			(layer "B.Fab")
		)
		(fp_line
			(start -0.12065 -0.3048)
			(end -0.67945 -0.3048)
			(stroke
				(width 0.1)
				(type default)
			)
			(layer "B.Fab")
		)
		(fp_line
			(start -0.67945 -0.3048)
			(end -0.67945 0.3048)
			(stroke
				(width 0.1)
				(type default)
			)
			(layer "B.Fab")
		)
		(fp_line
			(start 0.12065 -0.2794)
			(end -0.12065 -0.2794)
			(stroke
				(width 0.1)
				(type default)
			)
			(layer "B.Fab")
		)
		(fp_line
			(start -0.12065 -0.2794)
			(end -0.12065 -0.3048)
			(stroke
				(width 0.1)
				(type default)
			)
			(layer "B.Fab")
		)
		(fp_line
			(start 0.12065 0.2794)
			(end 0.12065 0.3048)
			(stroke
				(width 0.1)
				(type default)
			)
			(layer "B.Fab")
		)
		(fp_line
			(start -0.120396 0.2794)
			(end 0.12065 0.2794)
			(stroke
				(width 0.1)
				(type default)
			)
			(layer "B.Fab")
		)
		(fp_line
			(start 0.67945 0.3048)
			(end 0.67945 -0.305054)
			(stroke
				(width 0.1)
				(type default)
			)
			(layer "B.Fab")
		)
		(fp_line
			(start 0.12065 0.3048)
			(end 0.67945 0.3048)
			(stroke
				(width 0.1)
				(type default)
			)
			(layer "B.Fab")
		)
		(fp_line
			(start -0.120396 0.3048)
			(end -0.120396 0.2794)
			(stroke
				(width 0.1)
				(type default)
			)
			(layer "B.Fab")
		)
		(fp_line
			(start -0.67945 0.3048)
			(end -0.120396 0.3048)
			(stroke
				(width 0.1)
				(type default)
			)
			(layer "B.Fab")
		)
		(pad "1" smd circle
			(at 0.40005 0 270)
			(size 0 0)
			(layers "B.Cu" "B.Mask" "B.Paste")
			(net "SVID_ALERT0_CPU0_R_N")
		)
		(pad "2" smd circle
			(at -0.40005 0 270)
			(size 0 0)
			(layers "B.Cu" "B.Mask" "B.Paste")
			(net "PVNN_TERM_CPU0")
		)
	)
	(footprint ""
		(layer "B.Cu")
		(at 49.15408 -172.989748)
		(property "Reference" "PR4248"
			(at 0 0 0)
			(layer "B.SilkS")
			(hide yes)
			(effects
				(font
					(size 1.27 1.27)
				)
				(justify mirror)
			)
		)
		(property "Value" ""
			(at 0 0 0)
			(layer "B.Fab")
			(effects
				(font
					(size 1.27 1.27)
				)
				(justify mirror)
			)
		)
		(duplicate_pad_numbers_are_jumpers no)
		(fp_line
			(start -0.7874 -0.4064)
			(end -0.7874 0.4064)
			(stroke
				(width 0.1524)
				(type default)
			)
			(layer "B.SilkS")
		)
		(fp_line
			(start -0.7874 0.4064)
			(end 0.7874 0.4064)
			(stroke
				(width 0.1524)
				(type default)
			)
			(layer "B.SilkS")
		)
		(fp_line
			(start 0.7874 -0.4064)
			(end -0.7874 -0.4064)
			(stroke
				(width 0.1524)
				(type default)
			)
			(layer "B.SilkS")
		)
		(fp_line
			(start 0.7874 0.4064)
			(end 0.7874 -0.4064)
			(stroke
				(width 0.1524)
				(type default)
			)
			(layer "B.SilkS")
		)
		(fp_line
			(start -0.67945 -0.3048)
			(end -0.67945 0.3048)
			(stroke
				(width 0.1)
				(type default)
			)
			(layer "B.Fab")
		)
		(fp_line
			(start -0.67945 0.3048)
			(end -0.120396 0.3048)
			(stroke
				(width 0.1)
				(type default)
			)
			(layer "B.Fab")
		)
		(fp_line
			(start -0.12065 -0.3048)
			(end -0.67945 -0.3048)
			(stroke
				(width 0.1)
				(type default)
			)
			(layer "B.Fab")
		)
		(fp_line
			(start -0.12065 -0.2794)
			(end -0.12065 -0.3048)
			(stroke
				(width 0.1)
				(type default)
			)
			(layer "B.Fab")
		)
		(fp_line
			(start -0.120396 0.2794)
			(end 0.12065 0.2794)
			(stroke
				(width 0.1)
				(type default)
			)
			(layer "B.Fab")
		)
		(fp_line
			(start -0.120396 0.3048)
			(end -0.120396 0.2794)
			(stroke
				(width 0.1)
				(type default)
			)
			(layer "B.Fab")
		)
		(fp_line
			(start 0.12065 -0.305054)
			(end 0.12065 -0.2794)
			(stroke
				(width 0.1)
				(type default)
			)
			(layer "B.Fab")
		)
		(fp_line
			(start 0.12065 -0.2794)
			(end -0.12065 -0.2794)
			(stroke
				(width 0.1)
				(type default)
			)
			(layer "B.Fab")
		)
		(fp_line
			(start 0.12065 0.2794)
			(end 0.12065 0.3048)
			(stroke
				(width 0.1)
				(type default)
			)
			(layer "B.Fab")
		)
		(fp_line
			(start 0.12065 0.3048)
			(end 0.67945 0.3048)
			(stroke
				(width 0.1)
				(type default)
			)
			(layer "B.Fab")
		)
		(fp_line
			(start 0.67945 -0.305054)
			(end 0.12065 -0.305054)
			(stroke
				(width 0.1)
				(type default)
			)
			(layer "B.Fab")
		)
		(fp_line
			(start 0.67945 0.3048)
			(end 0.67945 -0.305054)
			(stroke
				(width 0.1)
				(type default)
			)
			(layer "B.Fab")
		)
		(pad "1" smd circle
			(at 0.40005 0 180)
			(size 0 0)
			(layers "B.Cu" "B.Mask" "B.Paste")
			(net "PVCCFA_EHV_CPU1_NC2")
		)
		(pad "2" smd circle
			(at -0.40005 0 180)
			(size 0 0)
			(layers "B.Cu" "B.Mask" "B.Paste")
			(net "PVCCFA_EHV_CPU1_VDD1")
		)
	)
	(footprint ""
		(layer "B.Cu")
		(at 430.600104 -137.542778)
		(property "Reference" "R2396"
			(at 0 0 0)
			(layer "B.SilkS")
			(hide yes)
			(effects
				(font
					(size 1.27 1.27)
				)
				(justify mirror)
			)
		)
		(property "Value" ""
			(at 0 0 0)
			(layer "B.Fab")
			(effects
				(font
					(size 1.27 1.27)
				)
				(justify mirror)
			)
		)
		(duplicate_pad_numbers_are_jumpers no)
		(fp_line
			(start -0.7874 -0.4064)
			(end -0.7874 0.4064)
			(stroke
				(width 0.1524)
				(type default)
			)
			(layer "B.SilkS")
		)
		(fp_line
			(start -0.7874 0.4064)
			(end 0.7874 0.4064)
			(stroke
				(width 0.1524)
				(type default)
			)
			(layer "B.SilkS")
		)
		(fp_line
			(start 0.7874 -0.4064)
			(end -0.7874 -0.4064)
			(stroke
				(width 0.1524)
				(type default)
			)
			(layer "B.SilkS")
		)
		(fp_line
			(start 0.7874 0.4064)
			(end 0.7874 -0.4064)
			(stroke
				(width 0.1524)
				(type default)
			)
			(layer "B.SilkS")
		)
		(fp_line
			(start -0.67945 -0.3048)
			(end -0.67945 0.3048)
			(stroke
				(width 0.1)
				(type default)
			)
			(layer "B.Fab")
		)
		(fp_line
			(start -0.67945 0.3048)
			(end -0.120396 0.3048)
			(stroke
				(width 0.1)
				(type default)
			)
			(layer "B.Fab")
		)
		(fp_line
			(start -0.12065 -0.3048)
			(end -0.67945 -0.3048)
			(stroke
				(width 0.1)
				(type default)
			)
			(layer "B.Fab")
		)
		(fp_line
			(start -0.12065 -0.2794)
			(end -0.12065 -0.3048)
			(stroke
				(width 0.1)
				(type default)
			)
			(layer "B.Fab")
		)
		(fp_line
			(start -0.120396 0.2794)
			(end 0.12065 0.2794)
			(stroke
				(width 0.1)
				(type default)
			)
			(layer "B.Fab")
		)
		(fp_line
			(start -0.120396 0.3048)
			(end -0.120396 0.2794)
			(stroke
				(width 0.1)
				(type default)
			)
			(layer "B.Fab")
		)
		(fp_line
			(start 0.12065 -0.305054)
			(end 0.12065 -0.2794)
			(stroke
				(width 0.1)
				(type default)
			)
			(layer "B.Fab")
		)
		(fp_line
			(start 0.12065 -0.2794)
			(end -0.12065 -0.2794)
			(stroke
				(width 0.1)
				(type default)
			)
			(layer "B.Fab")
		)
		(fp_line
			(start 0.12065 0.2794)
			(end 0.12065 0.3048)
			(stroke
				(width 0.1)
				(type default)
			)
			(layer "B.Fab")
		)
		(fp_line
			(start 0.12065 0.3048)
			(end 0.67945 0.3048)
			(stroke
				(width 0.1)
				(type default)
			)
			(layer "B.Fab")
		)
		(fp_line
			(start 0.67945 -0.305054)
			(end 0.12065 -0.305054)
			(stroke
				(width 0.1)
				(type default)
			)
			(layer "B.Fab")
		)
		(fp_line
			(start 0.67945 0.3048)
			(end 0.67945 -0.305054)
			(stroke
				(width 0.1)
				(type default)
			)
			(layer "B.Fab")
		)
		(pad "1" smd circle
			(at 0.40005 0 180)
			(size 0 0)
			(layers "B.Cu" "B.Mask" "B.Paste")
			(net "P3V3_AUX")
		)
		(pad "2" smd circle
			(at -0.40005 0 180)
			(size 0 0)
			(layers "B.Cu" "B.Mask" "B.Paste")
			(net "PWRGD_PVCCFA_EHV_CPU0_R")
		)
	)
	(footprint ""
		(layer "B.Cu")
		(at 61.62421 -147.84197)
		(property "Reference" "PC1588"
			(at 0 0 0)
			(layer "B.SilkS")
			(hide yes)
			(effects
				(font
					(size 1.27 1.27)
				)
				(justify mirror)
			)
		)
		(property "Value" ""
			(at 0 0 0)
			(layer "B.Fab")
			(effects
				(font
					(size 1.27 1.27)
				)
				(justify mirror)
			)
		)
		(duplicate_pad_numbers_are_jumpers no)
		(fp_line
			(start -4.53898 -2.15011)
			(end -4.53898 2.15011)
			(stroke
				(width 0.1524)
				(type default)
			)
			(layer "B.SilkS")
		)
		(fp_line
			(start -4.53898 2.15011)
			(end 4.53898 2.15011)
			(stroke
				(width 0.1524)
				(type default)
			)
			(layer "B.SilkS")
		)
		(fp_line
			(start 4.53898 -2.150618)
			(end 4.539742 2.152142)
			(stroke
				(width 0.1524)
				(type default)
			)
			(layer "B.SilkS")
		)
		(fp_line
			(start 4.53898 -2.15011)
			(end -4.53898 -2.15011)
			(stroke
				(width 0.1524)
				(type default)
			)
			(layer "B.SilkS")
		)
		(fp_line
			(start 4.53898 2.15011)
			(end 4.53898 -2.15011)
			(stroke
				(width 0.1524)
				(type default)
			)
			(layer "B.SilkS")
		)
		(fp_line
			(start 4.69138 -2.150618)
			(end 4.692396 2.161032)
			(stroke
				(width 0.1524)
				(type default)
			)
			(layer "B.SilkS")
		)
		(fp_line
			(start 4.83108 2.150364)
			(end 4.447794 2.149348)
			(stroke
				(width 0.1524)
				(type default)
			)
			(layer "B.SilkS")
		)
		(fp_line
			(start 4.84378 -2.150618)
			(end 4.53898 -2.150618)
			(stroke
				(width 0.1524)
				(type default)
			)
			(layer "B.SilkS")
		)
		(fp_line
			(start 4.84378 -2.150618)
			(end 4.842256 2.163064)
			(stroke
				(width 0.1524)
				(type default)
			)
			(layer "B.SilkS")
		)
		(fp_line
			(start -3.64998 -2.15011)
			(end -3.64998 2.15011)
			(stroke
				(width 0.1)
				(type default)
			)
			(layer "B.Fab")
		)
		(fp_line
			(start -3.64998 2.15011)
			(end 3.64998 2.15011)
			(stroke
				(width 0.1)
				(type default)
			)
			(layer "B.Fab")
		)
		(fp_line
			(start 3.64998 -2.15011)
			(end -3.64998 -2.15011)
			(stroke
				(width 0.1)
				(type default)
			)
			(layer "B.Fab")
		)
		(fp_line
			(start 3.64998 2.15011)
			(end 3.64998 -2.15011)
			(stroke
				(width 0.1)
				(type default)
			)
			(layer "B.Fab")
		)
		(fp_text user "-"
			(at -4.66979 0.700532 0)
			(unlocked yes)
			(layer "B.SilkS")
			(effects
				(font
					(size 1.905 1.4224)
					(thickness 0.1524)
				)
				(justify left mirror)
			)
		)
		(fp_text user "+"
			(at 6.214872 -0.337058 0)
			(unlocked yes)
			(layer "B.SilkS")
			(effects
				(font
					(size 1.905 1.4224)
					(thickness 0.1524)
				)
				(justify left mirror)
			)
		)
		(fp_text user "-"
			(at -4.313174 -0.094488 0)
			(unlocked yes)
			(layer "B.Fab")
			(effects
				(font
					(size 1.905 1.4224)
					(thickness 0.1524)
				)
				(justify left mirror)
			)
		)
		(fp_text user "+"
			(at 6.214872 -0.337058 0)
			(unlocked yes)
			(layer "B.Fab")
			(effects
				(font
					(size 1.905 1.4224)
					(thickness 0.1524)
				)
				(justify left mirror)
			)
		)
		(pad "1" smd rect
			(at 3.199892 0 180)
			(size 2.413 2.8194)
			(layers "B.Cu" "B.Mask" "B.Paste")
			(net "PVCCINFAON_CPU1")
		)
		(pad "2" smd rect
			(at -3.199892 0 180)
			(size 2.413 2.8194)
			(layers "B.Cu" "B.Mask" "B.Paste")
			(net "GND")
		)
	)
)
